# T6G (Grand Teton) — schematic netlist excerpt (pin names and nets, part order shuffled) for the footprints in the layout excerpt that follows; sources: Cadence DE-HDL packaged netlist, KiCad conversion of 04192023_DAF0TMB3IC0_F0TG_MB_C_brd_V02_OCP.brd

C50  Q_CAP_DIFFBUS  DIFF BUS_0.22UF 6.3V 20% X6S  pkg C0201  page 67 : \1\ = P5E_CPU1_P3_TX_C_DN<14> ; \2\ = P5E_CPU1_P3_TX_DN<14>

Q61  MOSFET_N_GSD  NX138BK IC  pkg SOT23_GDSXE  page 164
  DRAIN  = UART_LS_EN_R_N
  GATE  = UART_LS_EN
  SOURCE  = GND

R1435  Q_RES  10K 1% CHIP  pkg 0201LF  page 353 : A = RXDET_BYP_RT_CPU1_P3 ; B = GND
C2635  Q_CAP  22UF 4V 20% X6S  pkg C0402  page 70 : A = PVDD11_S3_P0 ; B = GND

(kicad_pcb
	(version 20260206)
	(generator "pcbnew")
	(generator_version "10.0")
	(general
		(thickness 1.6)
		(legacy_teardrops no)
	)
	(paper "A4")
	(title_block
		(title "04192023_DAF0TMB3IC0_F0TG_MB_C_brd_V02_OCP.brd")
		(comment 1 "Grand Teton / footprints 2503-2506 of 8354")
	)
	(layers
		(0 "F.Cu" signal "TOP")
		(4 "In1.Cu" signal "GND")
		(6 "In2.Cu" signal "IN1")
		(8 "In3.Cu" signal "GND1")
		(10 "In4.Cu" signal "IN2")
		(12 "In5.Cu" signal "GND2")
		(14 "In6.Cu" signal "IN3")
		(16 "In7.Cu" signal "GND3")
		(18 "In8.Cu" signal "VCC")
		(20 "In9.Cu" signal "VCC1")
		(22 "In10.Cu" signal "GND4")
		(24 "In11.Cu" signal "IN4")
		(26 "In12.Cu" signal "GND5")
		(28 "In13.Cu" signal "IN5")
		(30 "In14.Cu" signal "GND6")
		(32 "In15.Cu" signal "IN6")
		(34 "In16.Cu" signal "GND7")
		(2 "B.Cu" signal "BOTTOM")
		(9 "F.Adhes" user "F.Adhesive")
		(11 "B.Adhes" user "B.Adhesive")
		(13 "F.Paste" user "Package Geometry/Pastemask Top")
		(15 "B.Paste" user "Package Geometry/Pastemask Bottom")
		(5 "F.SilkS" user "Ref Des/Silkscreen Top")
		(7 "B.SilkS" user "Ref Des/Silkscreen Bottom")
		(1 "F.Mask" user "Board Geometry/Soldermask Top")
		(3 "B.Mask" user "Board Geometry/Soldermask Bottom")
		(17 "Dwgs.User" user "User.Drawings")
		(19 "Cmts.User" user "User.Comments")
		(21 "Eco1.User" user "User.Eco1")
		(23 "Eco2.User" user "User.Eco2")
		(25 "Edge.Cuts" user "Board Geometry/Outline")
		(27 "Margin" user)
		(31 "F.CrtYd" user "Package Geometry/Place Bound Top")
		(29 "B.CrtYd" user "Package Geometry/Place Bound Bottom")
		(35 "F.Fab" user "Ref Des/Assembly Top")
		(33 "B.Fab" user "Ref Des/Assembly Bottom")
	)
	(footprint ""
		(layer "F.Cu")
		(at 361.317032 -261.747762 -90)
		(property "Reference" "C2635"
			(at 0 0 270)
			(layer "F.SilkS")
			(hide yes)
			(effects
				(font
					(size 1.27 1.27)
				)
			)
		)
		(property "Value" ""
			(at 0 0 270)
			(layer "F.Fab")
			(effects
				(font
					(size 1.27 1.27)
				)
			)
		)
		(duplicate_pad_numbers_are_jumpers no)
		(fp_line
			(start -0.7874 0.4064)
			(end -0.7874 -0.4064)
			(stroke
				(width 0.1524)
				(type default)
			)
			(layer "F.SilkS")
		)
		(fp_line
			(start 0.7874 0.4064)
			(end -0.7874 0.4064)
			(stroke
				(width 0.1524)
				(type default)
			)
			(layer "F.SilkS")
		)
		(fp_line
			(start -0.7874 -0.4064)
			(end 0.7874 -0.4064)
			(stroke
				(width 0.1524)
				(type default)
			)
			(layer "F.SilkS")
		)
		(fp_line
			(start 0.7874 -0.4064)
			(end 0.7874 0.4064)
			(stroke
				(width 0.1524)
				(type default)
			)
			(layer "F.SilkS")
		)
		(fp_line
			(start -0.67945 0.3048)
			(end -0.67945 -0.305054)
			(stroke
				(width 0.1)
				(type default)
			)
			(layer "F.Fab")
		)
		(fp_line
			(start -0.12065 0.3048)
			(end -0.67945 0.3048)
			(stroke
				(width 0.1)
				(type default)
			)
			(layer "F.Fab")
		)
		(fp_line
			(start 0.120396 0.3048)
			(end 0.120396 0.2794)
			(stroke
				(width 0.1)
				(type default)
			)
			(layer "F.Fab")
		)
		(fp_line
			(start 0.67945 0.3048)
			(end 0.120396 0.3048)
			(stroke
				(width 0.1)
				(type default)
			)
			(layer "F.Fab")
		)
		(fp_line
			(start -0.12065 0.2794)
			(end -0.12065 0.3048)
			(stroke
				(width 0.1)
				(type default)
			)
			(layer "F.Fab")
		)
		(fp_line
			(start 0.120396 0.2794)
			(end -0.12065 0.2794)
			(stroke
				(width 0.1)
				(type default)
			)
			(layer "F.Fab")
		)
		(fp_line
			(start -0.12065 -0.2794)
			(end 0.12065 -0.2794)
			(stroke
				(width 0.1)
				(type default)
			)
			(layer "F.Fab")
		)
		(fp_line
			(start 0.12065 -0.2794)
			(end 0.12065 -0.3048)
			(stroke
				(width 0.1)
				(type default)
			)
			(layer "F.Fab")
		)
		(fp_line
			(start 0.12065 -0.3048)
			(end 0.67945 -0.3048)
			(stroke
				(width 0.1)
				(type default)
			)
			(layer "F.Fab")
		)
		(fp_line
			(start 0.67945 -0.3048)
			(end 0.67945 0.3048)
			(stroke
				(width 0.1)
				(type default)
			)
			(layer "F.Fab")
		)
		(fp_line
			(start -0.67945 -0.305054)
			(end -0.12065 -0.305054)
			(stroke
				(width 0.1)
				(type default)
			)
			(layer "F.Fab")
		)
		(fp_line
			(start -0.12065 -0.305054)
			(end -0.12065 -0.2794)
			(stroke
				(width 0.1)
				(type default)
			)
			(layer "F.Fab")
		)
		(pad "1" smd circle
			(at -0.40005 0 270)
			(size 0 0)
			(layers "F.Cu" "F.Mask" "F.Paste")
			(net "PVDD11_S3_P0")
		)
		(pad "2" smd circle
			(at 0.40005 0 270)
			(size 0 0)
			(layers "F.Cu" "F.Mask" "F.Paste")
			(net "GND")
		)
	)
	(footprint ""
		(layer "F.Cu")
		(at 138.2014 -389.27786 90)
		(property "Reference" "R1435"
			(at 0 0 90)
			(layer "F.SilkS")
			(hide yes)
			(effects
				(font
					(size 1.27 1.27)
				)
			)
		)
		(property "Value" ""
			(at 0 0 90)
			(layer "F.Fab")
			(effects
				(font
					(size 1.27 1.27)
				)
			)
		)
		(duplicate_pad_numbers_are_jumpers no)
		(fp_line
			(start 0.32512 -0.175006)
			(end 0.32512 0.175006)
			(stroke
				(width 0.1)
				(type default)
			)
			(layer "F.Fab")
		)
		(fp_line
			(start -0.32512 -0.175006)
			(end 0.32512 -0.175006)
			(stroke
				(width 0.1)
				(type default)
			)
			(layer "F.Fab")
		)
		(fp_line
			(start 0.32512 0.175006)
			(end -0.32512 0.175006)
			(stroke
				(width 0.1)
				(type default)
			)
			(layer "F.Fab")
		)
		(fp_line
			(start -0.32512 0.175006)
			(end -0.32512 -0.175006)
			(stroke
				(width 0.1)
				(type default)
			)
			(layer "F.Fab")
		)
		(pad "1" smd rect
			(at -0.2667 0 90)
			(size 0.3048 0.381)
			(layers "F.Cu" "F.Mask" "F.Paste")
			(net "RXDET_BYP_RT_CPU1_P3")
		)
		(pad "2" smd rect
			(at 0.2667 0 270)
			(size 0.3048 0.381)
			(layers "F.Cu" "F.Mask" "F.Paste")
			(net "GND")
		)
	)
	(footprint ""
		(layer "F.Cu")
		(at 358.959404 -28.695396)
		(property "Reference" "Q61"
			(at -0.26924 -2.352548 0)
			(unlocked yes)
			(layer "F.SilkS")
			(effects
				(font
					(size 0.7874 0.5842)
					(thickness 0.1524)
				)
			)
		)
		(property "Value" ""
			(at 0 0 0)
			(layer "F.Fab")
			(effects
				(font
					(size 1.27 1.27)
				)
			)
		)
		(duplicate_pad_numbers_are_jumpers no)
		(fp_line
			(start -1.8796 -1.651)
			(end 1.8796 -1.651)
			(stroke
				(width 0.1524)
				(type default)
			)
			(layer "F.SilkS")
		)
		(fp_line
			(start -1.8796 1.651)
			(end -1.8796 -1.651)
			(stroke
				(width 0.1524)
				(type default)
			)
			(layer "F.SilkS")
		)
		(fp_line
			(start 1.8796 -1.651)
			(end 1.8796 1.651)
			(stroke
				(width 0.1524)
				(type default)
			)
			(layer "F.SilkS")
		)
		(fp_line
			(start 1.8796 1.651)
			(end -1.8796 1.651)
			(stroke
				(width 0.1524)
				(type default)
			)
			(layer "F.SilkS")
		)
		(fp_line
			(start -0.700024 -1.500124)
			(end 0.700024 -1.500124)
			(stroke
				(width 0.1)
				(type default)
			)
			(layer "F.Fab")
		)
		(fp_line
			(start -0.700024 1.500124)
			(end -0.700024 -1.500124)
			(stroke
				(width 0.1)
				(type default)
			)
			(layer "F.Fab")
		)
		(fp_line
			(start 0.700024 -1.500124)
			(end 0.700024 1.500124)
			(stroke
				(width 0.1)
				(type default)
			)
			(layer "F.Fab")
		)
		(fp_line
			(start 0.700024 1.500124)
			(end -0.700024 1.500124)
			(stroke
				(width 0.1)
				(type default)
			)
			(layer "F.Fab")
		)
		(pad "D" smd rect
			(at 1.119886 0 270)
			(size 1.016 1.2192)
			(layers "F.Cu" "F.Mask" "F.Paste")
			(net "UART_LS_EN_R_N")
		)
		(pad "G" smd rect
			(at -1.119886 -0.999998 270)
			(size 1.016 1.2192)
			(layers "F.Cu" "F.Mask" "F.Paste")
			(net "UART_LS_EN")
		)
		(pad "S" smd rect
			(at -1.119886 0.999998 270)
			(size 1.016 1.2192)
			(layers "F.Cu" "F.Mask" "F.Paste")
			(net "GND")
		)
	)
	(footprint ""
		(layer "F.Cu")
		(at 136.840976 -376.067828)
		(property "Reference" "C50"
			(at 0 0 0)
			(layer "F.SilkS")
			(hide yes)
			(effects
				(font
					(size 1.27 1.27)
				)
			)
		)
		(property "Value" ""
			(at 0 0 0)
			(layer "F.Fab")
			(effects
				(font
					(size 1.27 1.27)
				)
			)
		)
		(duplicate_pad_numbers_are_jumpers no)
		(fp_line
			(start -0.299974 -0.150114)
			(end 0.299974 -0.150114)
			(stroke
				(width 0.1)
				(type default)
			)
			(layer "F.Fab")
		)
		(fp_line
			(start -0.299974 0.150114)
			(end -0.299974 -0.150114)
			(stroke
				(width 0.1)
				(type default)
			)
			(layer "F.Fab")
		)
		(fp_line
			(start 0.299974 -0.150114)
			(end 0.299974 0.150114)
			(stroke
				(width 0.1)
				(type default)
			)
			(layer "F.Fab")
		)
		(fp_line
			(start 0.299974 0.150114)
			(end -0.299974 0.150114)
			(stroke
				(width 0.1)
				(type default)
			)
			(layer "F.Fab")
		)
		(pad "1" smd rect
			(at -0.2667 0)
			(size 0.3048 0.381)
			(layers "F.Cu" "F.Mask" "F.Paste")
			(net "P5E_CPU1_P3_TX_C_DN<14>")
		)
		(pad "2" smd rect
			(at 0.2667 0)
			(size 0.3048 0.381)
			(layers "F.Cu" "F.Mask" "F.Paste")
			(net "P5E_CPU1_P3_TX_DN<14>")
		)
	)
)
